(kicad_pcb
	(version 20260206)
	(generator "pcbnew")
	(generator_version "10.0")
	(general
		(thickness 1.6)
		(legacy_teardrops no)
	)
	(paper "A4")
	(title_block
		(title "Wiwynn_Tioga_Pass_MB.brd")
		(comment 1 "Tioga Pass / footprints 2248-2251 of 4770")
	)
	(layers
		(0 "F.Cu" signal "TOP")
		(4 "In1.Cu" signal "L2GND")
		(6 "In2.Cu" signal "L3")
		(8 "In3.Cu" signal "L4GND")
		(10 "In4.Cu" signal "L5")
		(12 "In5.Cu" signal "L6GND")
		(14 "In6.Cu" signal "L7VCC")
		(16 "In7.Cu" signal "L8VCC")
		(18 "In8.Cu" signal "L9GND")
		(20 "In9.Cu" signal "L10")
		(22 "In10.Cu" signal "L11GND")
		(24 "In11.Cu" signal "L12")
		(26 "In12.Cu" signal "L13GND")
		(2 "B.Cu" signal "BOTTOM")
		(9 "F.Adhes" user "F.Adhesive")
		(11 "B.Adhes" user "B.Adhesive")
		(13 "F.Paste" user "Package Geometry/Pastemask Top")
		(15 "B.Paste" user "Package Geometry/Pastemask Bottom")
		(5 "F.SilkS" user "Ref Des/Silkscreen Top")
		(7 "B.SilkS" user "Ref Des/Silkscreen Bottom")
		(1 "F.Mask" user "Board Geometry/Soldermask Top")
		(3 "B.Mask" user "Board Geometry/Soldermask Bottom")
		(17 "Dwgs.User" user "User.Drawings")
		(19 "Cmts.User" user "User.Comments")
		(21 "Eco1.User" user "User.Eco1")
		(23 "Eco2.User" user "User.Eco2")
		(25 "Edge.Cuts" user "Board Geometry/Outline")
		(27 "Margin" user)
		(31 "F.CrtYd" user "Package Geometry/Place Bound Top")
		(29 "B.CrtYd" user "Package Geometry/Place Bound Bottom")
		(35 "F.Fab" user "Ref Des/Assembly Top")
		(33 "B.Fab" user "Ref Des/Assembly Bottom")
	)
	(footprint ""
		(layer "F.Cu")
		(at 386.326888 -78.388718)
		(property "Reference" "U7D2"
			(at -0.070104 -1.190752 0)
			(unlocked yes)
			(layer "F.SilkS")
			(effects
				(font
					(size 0.7874 0.5842)
					(thickness 0.1524)
				)
				(justify left)
			)
		)
		(property "Value" ""
			(at 0 0 0)
			(layer "F.Fab")
			(effects
				(font
					(size 1.27 1.27)
				)
			)
		)
		(duplicate_pad_numbers_are_jumpers no)
		(fp_line
			(start 1.5367 -0.64008)
			(end 4.4323 -0.64008)
			(stroke
				(width 0.1524)
				(type default)
			)
			(layer "F.SilkS")
		)
		(fp_line
			(start 1.5367 4.52628)
			(end 1.5367 -0.64008)
			(stroke
				(width 0.1524)
				(type default)
			)
			(layer "F.SilkS")
		)
		(fp_line
			(start 2.667 -0.64008)
			(end 2.667 0.49022)
			(stroke
				(width 0.1524)
				(type default)
			)
			(layer "F.SilkS")
		)
		(fp_line
			(start 2.667 0.49022)
			(end 3.302 0.49022)
			(stroke
				(width 0.1524)
				(type default)
			)
			(layer "F.SilkS")
		)
		(fp_line
			(start 3.302 0.49022)
			(end 3.302 -0.64008)
			(stroke
				(width 0.1524)
				(type default)
			)
			(layer "F.SilkS")
		)
		(fp_line
			(start 4.4323 -0.64008)
			(end 4.4323 4.52628)
			(stroke
				(width 0.1524)
				(type default)
			)
			(layer "F.SilkS")
		)
		(fp_line
			(start 4.4323 4.52628)
			(end 1.5367 4.52628)
			(stroke
				(width 0.1524)
				(type default)
			)
			(layer "F.SilkS")
		)
		(fp_circle
			(center -1.612138 -0.684784)
			(end -1.485138 -0.684784)
			(stroke
				(width 0.254)
				(type default)
			)
			(fill no)
			(layer "F.SilkS")
		)
		(fp_poly
			(pts
				(xy 0.7366 4.54152) (xy 0.7366 -0.64008) (xy 4.7244 -0.64008) (xy 5.2324 -0.64008) (xy 5.2324 4.54152)
				(xy 4.7244 4.54152)
			)
			(stroke
				(width 0)
				(type default)
			)
			(fill no)
			(layer "F.CrtYd")
		)
		(fp_line
			(start 0.7366 -0.64008)
			(end 5.2324 -0.64008)
			(stroke
				(width 0.1)
				(type default)
			)
			(layer "F.Fab")
		)
		(fp_line
			(start 0.7366 4.54152)
			(end 0.7366 -0.64008)
			(stroke
				(width 0.1)
				(type default)
			)
			(layer "F.Fab")
		)
		(fp_line
			(start 2.667 -0.64008)
			(end 2.667 0.49022)
			(stroke
				(width 0.1)
				(type default)
			)
			(layer "F.Fab")
		)
		(fp_line
			(start 2.667 0.49022)
			(end 3.302 0.49022)
			(stroke
				(width 0.1)
				(type default)
			)
			(layer "F.Fab")
		)
		(fp_line
			(start 3.302 0.49022)
			(end 3.302 -0.64008)
			(stroke
				(width 0.1)
				(type default)
			)
			(layer "F.Fab")
		)
		(fp_line
			(start 5.2324 -0.64008)
			(end 5.2324 4.54152)
			(stroke
				(width 0.1)
				(type default)
			)
			(layer "F.Fab")
		)
		(fp_line
			(start 5.2324 4.54152)
			(end 0.7366 4.54152)
			(stroke
				(width 0.1)
				(type default)
			)
			(layer "F.Fab")
		)
		(fp_circle
			(center -1.612138 -0.684784)
			(end -1.485138 -0.684784)
			(stroke
				(width 0.254)
				(type default)
			)
			(fill no)
			(layer "F.Fab")
		)
		(pad "1" smd rect
			(at 0 0)
			(size 2.159 0.381)
			(layers "F.Cu" "F.Mask" "F.Paste")
			(net "PD_GTL2104_DIR_0")
		)
		(pad "2" smd rect
			(at 0 0.65024)
			(size 2.159 0.381)
			(layers "F.Cu" "F.Mask" "F.Paste")
			(net "H_CPU_MSMI_G_N")
		)
		(pad "3" smd rect
			(at 0 1.30048)
			(size 2.159 0.381)
			(layers "F.Cu" "F.Mask" "F.Paste")
			(net "H_CPU0_FIVR_FAULT_G")
		)
		(pad "4" smd rect
			(at 0 1.95072)
			(size 2.159 0.381)
			(layers "F.Cu" "F.Mask" "F.Paste")
			(net "P0V7_GTL2104_VREF_0")
		)
		(pad "5" smd rect
			(at 0 2.60096)
			(size 2.159 0.381)
			(layers "F.Cu" "F.Mask" "F.Paste")
			(net "H_CPU_ERR2_GTL_N")
		)
		(pad "6" smd rect
			(at 0 3.2512)
			(size 2.159 0.381)
			(layers "F.Cu" "F.Mask" "F.Paste")
			(net "H_CPU0_THERMTRIP_G_N")
		)
		(pad "7" smd rect
			(at 0 3.90144)
			(size 2.159 0.381)
			(layers "F.Cu" "F.Mask" "F.Paste")
			(net "GND")
		)
		(pad "8" smd rect
			(at 5.969 3.90144)
			(size 2.159 0.381)
			(layers "F.Cu" "F.Mask" "F.Paste")
			(net "GND")
		)
		(pad "9" smd rect
			(at 5.969 3.2512)
			(size 2.159 0.381)
			(layers "F.Cu" "F.Mask" "F.Paste")
			(net "FM_CPU0_THERMTRIP_LVT3_R_N")
		)
		(pad "10" smd rect
			(at 5.969 2.60096)
			(size 2.159 0.381)
			(layers "F.Cu" "F.Mask" "F.Paste")
			(net "FM_CPU_ERR2_LVT3_R_N")
		)
		(pad "11" smd rect
			(at 5.969 1.95072)
			(size 2.159 0.381)
			(layers "F.Cu" "F.Mask" "F.Paste")
			(net "GND")
		)
		(pad "12" smd rect
			(at 5.969 1.30048)
			(size 2.159 0.381)
			(layers "F.Cu" "F.Mask" "F.Paste")
			(net "FM_CPU0_FIVR_FAULT_R_LVT3")
		)
		(pad "13" smd rect
			(at 5.969 0.65024)
			(size 2.159 0.381)
			(layers "F.Cu" "F.Mask" "F.Paste")
			(net "FM_CPU_MSMI_LVT3_R_N")
		)
		(pad "14" smd rect
			(at 5.969 0)
			(size 2.159 0.381)
			(layers "F.Cu" "F.Mask" "F.Paste")
			(net "P3V3")
		)
	)
	(footprint ""
		(layer "F.Cu")
		(at 10.362184 -3.532124 180)
		(property "Reference" "R1G10"
			(at 0 0 180)
			(layer "F.SilkS")
			(hide yes)
			(effects
				(font
					(size 1.27 1.27)
				)
			)
		)
		(property "Value" ""
			(at 0 0 180)
			(layer "F.Fab")
			(effects
				(font
					(size 1.27 1.27)
				)
			)
		)
		(duplicate_pad_numbers_are_jumpers no)
		(fp_rect
			(start 0.2794 0.9906)
			(end -0.2794 -0.1016)
			(stroke
				(width 0)
				(type default)
			)
			(fill no)
			(layer "F.CrtYd")
		)
		(fp_line
			(start 0.2794 0.9906)
			(end 0.2794 -0.1016)
			(stroke
				(width 0.1)
				(type default)
			)
			(layer "F.Fab")
		)
		(fp_line
			(start 0.2794 -0.1016)
			(end -0.2794 -0.1016)
			(stroke
				(width 0.1)
				(type default)
			)
			(layer "F.Fab")
		)
		(fp_line
			(start -0.2794 0.9906)
			(end 0.2794 0.9906)
			(stroke
				(width 0.1)
				(type default)
			)
			(layer "F.Fab")
		)
		(fp_line
			(start -0.2794 -0.1016)
			(end -0.2794 0.9906)
			(stroke
				(width 0.1)
				(type default)
			)
			(layer "F.Fab")
		)
		(pad "1" smd rect
			(at 0 0 180)
			(size 0.508 0.508)
			(layers "F.Cu" "F.Mask" "F.Paste")
			(net "SVID_VDIO_PVDDQ_GHJ")
		)
		(pad "2" smd rect
			(at 0 0.889 180)
			(size 0.508 0.508)
			(layers "F.Cu" "F.Mask" "F.Paste")
			(net "SVID_DIO1_CPU1_R")
		)
		(zone
			(layer "F.Cu")
			(hatch none 0.5)
			(connect_pads
				(clearance 0)
			)
			(min_thickness 0.25)
			(keepout
				(tracks not_allowed)
				(vias allowed)
				(pads allowed)
				(copperpour not_allowed)
				(footprints allowed)
			)
			(placement
				(enabled no)
				(sheetname "")
			)
			(fill
				(thermal_gap 0.5)
				(thermal_bridge_width 0.5)
				(island_removal_mode 0)
			)
			(polygon
				(pts
					(xy 10.108184 -4.167124) (xy 10.108184 -3.786124) (xy 10.616184 -3.786124) (xy 10.616184 -4.167124)
				)
			)
		)
		(zone
			(layer "F.Cu")
			(hatch none 0.5)
			(connect_pads
				(clearance 0)
			)
			(min_thickness 0.25)
			(keepout
				(tracks allowed)
				(vias not_allowed)
				(pads allowed)
				(copperpour not_allowed)
				(footprints allowed)
			)
			(placement
				(enabled no)
				(sheetname "")
			)
			(fill
				(thermal_gap 0.5)
				(thermal_bridge_width 0.5)
				(island_removal_mode 0)
			)
			(polygon
				(pts
					(xy 10.108184 -4.167124) (xy 10.108184 -3.786124) (xy 10.616184 -3.786124) (xy 10.616184 -4.167124)
				)
			)
		)
	)
	(footprint ""
		(layer "F.Cu")
		(at 394.72235 -78.462886 90)
		(property "Reference" "R7D25"
			(at 0 0 90)
			(layer "F.SilkS")
			(hide yes)
			(effects
				(font
					(size 1.27 1.27)
				)
			)
		)
		(property "Value" ""
			(at 0 0 90)
			(layer "F.Fab")
			(effects
				(font
					(size 1.27 1.27)
				)
			)
		)
		(duplicate_pad_numbers_are_jumpers no)
		(fp_poly
			(pts
				(xy -0.2794 -0.1016) (xy 0.2794 -0.1016) (xy 0.2794 0.9906) (xy -0.2794 0.9906)
			)
			(stroke
				(width 0)
				(type default)
			)
			(fill no)
			(layer "F.CrtYd")
		)
		(fp_line
			(start 0.2794 -0.1016)
			(end -0.2794 -0.1016)
			(stroke
				(width 0.1)
				(type default)
			)
			(layer "F.Fab")
		)
		(fp_line
			(start -0.2794 -0.1016)
			(end -0.2794 0.9906)
			(stroke
				(width 0.1)
				(type default)
			)
			(layer "F.Fab")
		)
		(fp_line
			(start 0.2794 0.9906)
			(end 0.2794 -0.1016)
			(stroke
				(width 0.1)
				(type default)
			)
			(layer "F.Fab")
		)
		(fp_line
			(start -0.2794 0.9906)
			(end 0.2794 0.9906)
			(stroke
				(width 0.1)
				(type default)
			)
			(layer "F.Fab")
		)
		(pad "1" smd rect
			(at 0 0 90)
			(size 0.508 0.508)
			(layers "F.Cu" "F.Mask" "F.Paste")
			(net "FM_CPU_MSMI_LVT3_R_N")
		)
		(pad "2" smd rect
			(at 0 0.889 90)
			(size 0.508 0.508)
			(layers "F.Cu" "F.Mask" "F.Paste")
			(net "FM_CPU_MSMI_LVT3_N")
		)
		(zone
			(layer "F.Cu")
			(hatch none 0.5)
			(connect_pads
				(clearance 0)
			)
			(min_thickness 0.25)
			(keepout
				(tracks allowed)
				(vias not_allowed)
				(pads allowed)
				(copperpour not_allowed)
				(footprints allowed)
			)
			(placement
				(enabled no)
				(sheetname "")
			)
			(fill
				(thermal_gap 0.5)
				(thermal_bridge_width 0.5)
				(island_removal_mode 0)
			)
			(polygon
				(pts
					(xy 394.97635 -78.208886) (xy 394.97635 -78.716886) (xy 395.35735 -78.716886) (xy 395.35735 -78.208886)
				)
			)
		)
		(zone
			(layer "F.Cu")
			(hatch none 0.5)
			(connect_pads
				(clearance 0)
			)
			(min_thickness 0.25)
			(keepout
				(tracks not_allowed)
				(vias allowed)
				(pads allowed)
				(copperpour not_allowed)
				(footprints allowed)
			)
			(placement
				(enabled no)
				(sheetname "")
			)
			(fill
				(thermal_gap 0.5)
				(thermal_bridge_width 0.5)
				(island_removal_mode 0)
			)
			(polygon
				(pts
					(xy 395.35735 -78.208886) (xy 395.35735 -78.716886) (xy 394.97635 -78.716886) (xy 394.97635 -78.208886)
				)
			)
		)
	)
	(footprint ""
		(layer "F.Cu")
		(at 4.962906 -9.493758 90)
		(property "Reference" "EU1G1"
			(at -1.289558 -4.047236 90)
			(unlocked yes)
			(layer "F.SilkS")
			(effects
				(font
					(size 0.7874 0.5842)
					(thickness 0.1524)
				)
			)
		)
		(property "Value" ""
			(at 0 0 90)
			(layer "F.Fab")
			(effects
				(font
					(size 1.27 1.27)
				)
			)
		)
		(duplicate_pad_numbers_are_jumpers no)
		(fp_line
			(start 2.9718 -3.5052)
			(end 2.9718 3.429)
			(stroke
				(width 0.1524)
				(type default)
			)
			(layer "F.SilkS")
		)
		(fp_line
			(start -3.0099 -3.5052)
			(end 2.9718 -3.5052)
			(stroke
				(width 0.1524)
				(type default)
			)
			(layer "F.SilkS")
		)
		(fp_line
			(start 2.9718 3.429)
			(end -3.0099 3.429)
			(stroke
				(width 0.1524)
				(type default)
			)
			(layer "F.SilkS")
		)
		(fp_line
			(start -3.0099 3.429)
			(end -3.0099 -3.5052)
			(stroke
				(width 0.1524)
				(type default)
			)
			(layer "F.SilkS")
		)
		(fp_circle
			(center -3.057398 -2.678684)
			(end -3.057398 -2.551684)
			(stroke
				(width 0.254)
				(type default)
			)
			(fill no)
			(layer "F.SilkS")
		)
		(fp_poly
			(pts
				(xy -2.9972 -3.4925) (xy -2.9972 -2.6924) (xy -2.1971 -3.4925)
			)
			(stroke
				(width 0)
				(type default)
			)
			(fill yes)
			(layer "F.SilkS")
		)
		(fp_poly
			(pts
				(xy -2.549906 -3.050032) (xy -2.549906 3.050032) (xy 2.549906 3.050032) (xy 2.549906 -3.050032)
			)
			(stroke
				(width 0)
				(type default)
			)
			(fill no)
			(layer "F.CrtYd")
		)
		(fp_line
			(start 2.549906 -3.050032)
			(end 2.549906 3.050032)
			(stroke
				(width 0.1)
				(type default)
			)
			(layer "F.Fab")
		)
		(fp_line
			(start -2.549906 -3.050032)
			(end 2.549906 -3.050032)
			(stroke
				(width 0.1)
				(type default)
			)
			(layer "F.Fab")
		)
		(fp_line
			(start 2.549906 3.050032)
			(end -2.549906 3.050032)
			(stroke
				(width 0.1)
				(type default)
			)
			(layer "F.Fab")
		)
		(fp_line
			(start -2.549906 3.050032)
			(end -2.549906 -3.050032)
			(stroke
				(width 0.1)
				(type default)
			)
			(layer "F.Fab")
		)
		(fp_circle
			(center -3.057398 -2.678684)
			(end -3.057398 -2.551684)
			(stroke
				(width 0.254)
				(type default)
			)
			(fill no)
			(layer "F.Fab")
		)
		(pad "1" smd rect
			(at -2.39522 -2.279904 90)
			(size 0.7112 0.254)
			(layers "F.Cu" "F.Mask" "F.Paste")
			(net "PVDDQ_GHJ")
		)
		(pad "2" smd rect
			(at -2.39522 -1.83007 90)
			(size 0.7112 0.254)
			(layers "F.Cu" "F.Mask" "F.Paste")
			(net "GND")
		)
		(pad "3" smd rect
			(at -2.39522 -1.379982 90)
			(size 0.7112 0.254)
			(layers "F.Cu" "F.Mask" "F.Paste")
			(net "VR_PVDDQ_GHJ_PH1_VCIN")
		)
		(pad "4" smd rect
			(at -2.39522 -0.929894 90)
			(size 0.7112 0.254)
			(layers "F.Cu" "F.Mask" "F.Paste")
			(net "P5V_STBY")
		)
		(pad "5" smd rect
			(at -2.39522 -0.48006 90)
			(size 0.7112 0.254)
			(layers "F.Cu" "F.Mask" "F.Paste")
			(net "GND")
		)
		(pad "6" smd rect
			(at -2.39522 -0.029972 90)
			(size 0.7112 0.254)
			(layers "F.Cu" "F.Mask" "F.Paste")
			(net "TP_PVDDQ_GHJ_PH1_GL_0")
		)
		(pad "7" smd custom
			(at 0.016764 1.145032 90)
			(size 0.53975 0.53975)
			(layers "F.Cu" "F.Mask" "F.Paste")
			(net "GND")
			(options
				(clearance outline)
				(anchor circle)
			)
			(primitives
				(gr_poly
					(pts
						(xy -2.7051 1.0795) (xy -2.7051 -0.3683) (xy -0.9271 -0.3683) (xy -0.9271 -1.0795) (xy 2.7051 -1.0795)
						(xy 2.7051 1.0795)
					)
					(width 0)
					(fill yes)
				)
			)
		)
		(pad "10" smd rect
			(at -0.008382 2.874772 90)
			(size 4.3434 0.6096)
			(layers "F.Cu" "F.Mask" "F.Paste")
			(net "VR_PVDDQ_GHJ_PH1_SW")
		)
		(pad "25" smd rect
			(at 1.548384 -1.283208 90)
			(size 2.3368 2.0066)
			(layers "F.Cu" "F.Mask" "F.Paste")
			(net "VR_FET_SW_P12V_STBY_PVDDQ_GHJ")
		)
		(pad "30" smd rect
			(at 2.050034 -2.895092 90)
			(size 0.254 0.7112)
			(layers "F.Cu" "F.Mask" "F.Paste")
			(net "VR_FET_SW_P12V_STBY_PVDDQ_GHJ")
		)
		(pad "31" smd rect
			(at 1.599946 -2.895092 90)
			(size 0.254 0.7112)
			(layers "F.Cu" "F.Mask" "F.Paste")
			(net "Net_296")
		)
		(pad "32" smd rect
			(at 1.150112 -2.895092 90)
			(size 0.254 0.7112)
			(layers "F.Cu" "F.Mask" "F.Paste")
			(net "VR_PVDDQ_GHJ_PH1_PHASE")
		)
		(pad "33" smd rect
			(at 0.700024 -2.895092 90)
			(size 0.254 0.7112)
			(layers "F.Cu" "F.Mask" "F.Paste")
			(net "VR_PVDDQ_GHJ_PH1_BOOT_R")
		)
		(pad "34" smd rect
			(at 0.249936 -2.895092 90)
			(size 0.254 0.7112)
			(layers "F.Cu" "F.Mask" "F.Paste")
			(net "VR_PVDDQ_GHJ_PWM1")
		)
		(pad "35" smd rect
			(at -0.199898 -2.895092 90)
			(size 0.254 0.7112)
			(layers "F.Cu" "F.Mask" "F.Paste")
			(net "P5V_STBY")
		)
		(pad "36" smd rect
			(at -0.649986 -2.895092 90)
			(size 0.254 0.7112)
			(layers "F.Cu" "F.Mask" "F.Paste")
			(net "A_TSENSE_PVDDQ_GHJ")
		)
		(pad "37" smd rect
			(at -1.100074 -2.895092 90)
			(size 0.254 0.7112)
			(layers "F.Cu" "F.Mask" "F.Paste")
			(net "VR_PVDDQ_GHJ_PH1_OCSET")
		)
		(pad "38" smd rect
			(at -1.549908 -2.895092 90)
			(size 0.254 0.7112)
			(layers "F.Cu" "F.Mask" "F.Paste")
			(net "ISENSE_PVDDQ_GHJ_PH1_IMON")
		)
		(pad "39" smd rect
			(at -1.999996 -2.895092 90)
			(size 0.254 0.7112)
			(layers "F.Cu" "F.Mask" "F.Paste")
			(net "VR_PVDDQ_GHJ_AIREF1")
		)
		(pad "40" smd rect
			(at -0.871728 -1.283208 90)
			(size 1.8034 2.0066)
			(layers "F.Cu" "F.Mask" "F.Paste")
			(net "GND")
		)
		(pad "41" smd rect
			(at -1.533906 0.247904 90)
			(size 0.508 0.3556)
			(layers "F.Cu" "F.Mask" "F.Paste")
			(net "TP_PVDDQ_GHJ_PH1_GL_1")
		)
	)
)
